# SCM (Grand Teton) — schematic netlist excerpt (pin names and nets, part order shuffled) for the footprints in the layout excerpt that follows; sources: Cadence DE-HDL packaged netlist, KiCad conversion of 12092022_DA0F0TMDCD0_F0T_Management_Board_D_brd_V3_OCP.brd

R239  Q_RES  4.7K 1% CHIP  pkg 0402LF  page 13 : A = P3V3_AUX ; B = PU_BMC_FWSPIABR_N
R781  Q_RES  0 5% EMPTY  pkg 0402LF  page 17 : A = P1V8_AUX ; B = ADCVREFEXT1

(kicad_pcb
	(version 20260206)
	(generator "pcbnew")
	(generator_version "10.0")
	(general
		(thickness 1.6)
		(legacy_teardrops no)
	)
	(paper "A4")
	(title_block
		(title "12092022_DA0F0TMDCD0_F0T_Management_Board_D_brd_V3_OCP.brd")
		(comment 1 "Grand Teton / footprints 727-728 of 1440")
	)
	(layers
		(0 "F.Cu" signal "TOP")
		(4 "In1.Cu" signal "GND")
		(6 "In2.Cu" signal "IN1")
		(8 "In3.Cu" signal "GND1")
		(10 "In4.Cu" signal "IN2")
		(12 "In5.Cu" signal "VCC")
		(14 "In6.Cu" signal "VCC1")
		(16 "In7.Cu" signal "IN3")
		(18 "In8.Cu" signal "GND2")
		(20 "In9.Cu" signal "IN4")
		(22 "In10.Cu" signal "GND3")
		(2 "B.Cu" signal "BOTTOM")
		(9 "F.Adhes" user "F.Adhesive")
		(11 "B.Adhes" user "B.Adhesive")
		(13 "F.Paste" user "Package Geometry/Pastemask Top")
		(15 "B.Paste" user "Package Geometry/Pastemask Bottom")
		(5 "F.SilkS" user "Ref Des/Silkscreen Top")
		(7 "B.SilkS" user "Ref Des/Silkscreen Bottom")
		(1 "F.Mask" user "Board Geometry/Soldermask Top")
		(3 "B.Mask" user "Board Geometry/Soldermask Bottom")
		(17 "Dwgs.User" user "User.Drawings")
		(19 "Cmts.User" user "User.Comments")
		(21 "Eco1.User" user "User.Eco1")
		(23 "Eco2.User" user "User.Eco2")
		(25 "Edge.Cuts" user "Board Geometry/Outline")
		(27 "Margin" user)
		(31 "F.CrtYd" user "Package Geometry/Place Bound Top")
		(29 "B.CrtYd" user "Package Geometry/Place Bound Bottom")
		(35 "F.Fab" user "Ref Des/Assembly Top")
		(33 "B.Fab" user "Ref Des/Assembly Bottom")
	)
	(footprint ""
		(layer "B.Cu")
		(at 52.891182 -72.842628 180)
		(property "Reference" "R781"
			(at 0 0 0)
			(layer "B.SilkS")
			(hide yes)
			(effects
				(font
					(size 1.27 1.27)
				)
				(justify mirror)
			)
		)
		(property "Value" ""
			(at 0 0 0)
			(layer "B.Fab")
			(effects
				(font
					(size 1.27 1.27)
				)
				(justify mirror)
			)
		)
		(duplicate_pad_numbers_are_jumpers no)
		(fp_line
			(start 0.7874 0.4064)
			(end 0.7874 -0.4064)
			(stroke
				(width 0.1524)
				(type default)
			)
			(layer "B.SilkS")
		)
		(fp_line
			(start 0.7874 -0.4064)
			(end -0.7874 -0.4064)
			(stroke
				(width 0.1524)
				(type default)
			)
			(layer "B.SilkS")
		)
		(fp_line
			(start -0.7874 0.4064)
			(end 0.7874 0.4064)
			(stroke
				(width 0.1524)
				(type default)
			)
			(layer "B.SilkS")
		)
		(fp_line
			(start -0.7874 -0.4064)
			(end -0.7874 0.4064)
			(stroke
				(width 0.1524)
				(type default)
			)
			(layer "B.SilkS")
		)
		(fp_line
			(start 0.67945 0.3048)
			(end 0.67945 -0.305054)
			(stroke
				(width 0.1)
				(type default)
			)
			(layer "B.Fab")
		)
		(fp_line
			(start 0.67945 -0.305054)
			(end 0.12065 -0.305054)
			(stroke
				(width 0.1)
				(type default)
			)
			(layer "B.Fab")
		)
		(fp_line
			(start 0.12065 0.3048)
			(end 0.67945 0.3048)
			(stroke
				(width 0.1)
				(type default)
			)
			(layer "B.Fab")
		)
		(fp_line
			(start 0.12065 0.2794)
			(end 0.12065 0.3048)
			(stroke
				(width 0.1)
				(type default)
			)
			(layer "B.Fab")
		)
		(fp_line
			(start 0.12065 -0.2794)
			(end -0.12065 -0.2794)
			(stroke
				(width 0.1)
				(type default)
			)
			(layer "B.Fab")
		)
		(fp_line
			(start 0.12065 -0.305054)
			(end 0.12065 -0.2794)
			(stroke
				(width 0.1)
				(type default)
			)
			(layer "B.Fab")
		)
		(fp_line
			(start -0.120396 0.3048)
			(end -0.120396 0.2794)
			(stroke
				(width 0.1)
				(type default)
			)
			(layer "B.Fab")
		)
		(fp_line
			(start -0.120396 0.2794)
			(end 0.12065 0.2794)
			(stroke
				(width 0.1)
				(type default)
			)
			(layer "B.Fab")
		)
		(fp_line
			(start -0.12065 -0.2794)
			(end -0.12065 -0.3048)
			(stroke
				(width 0.1)
				(type default)
			)
			(layer "B.Fab")
		)
		(fp_line
			(start -0.12065 -0.3048)
			(end -0.67945 -0.3048)
			(stroke
				(width 0.1)
				(type default)
			)
			(layer "B.Fab")
		)
		(fp_line
			(start -0.67945 0.3048)
			(end -0.120396 0.3048)
			(stroke
				(width 0.1)
				(type default)
			)
			(layer "B.Fab")
		)
		(fp_line
			(start -0.67945 -0.3048)
			(end -0.67945 0.3048)
			(stroke
				(width 0.1)
				(type default)
			)
			(layer "B.Fab")
		)
		(pad "1" smd circle
			(at 0.40005 0)
			(size 0 0)
			(layers "B.Cu" "B.Mask" "B.Paste")
			(net "P1V8_AUX")
		)
		(pad "2" smd circle
			(at -0.40005 0)
			(size 0 0)
			(layers "B.Cu" "B.Mask" "B.Paste")
			(net "ADCVREFEXT1")
		)
	)
	(footprint ""
		(layer "B.Cu")
		(at 56.6674 -63.7032 90)
		(property "Reference" "R239"
			(at 0 0 90)
			(layer "B.SilkS")
			(hide yes)
			(effects
				(font
					(size 1.27 1.27)
				)
				(justify mirror)
			)
		)
		(property "Value" ""
			(at 0 0 90)
			(layer "B.Fab")
			(effects
				(font
					(size 1.27 1.27)
				)
				(justify mirror)
			)
		)
		(duplicate_pad_numbers_are_jumpers no)
		(fp_line
			(start 0.7874 -0.4064)
			(end -0.7874 -0.4064)
			(stroke
				(width 0.1524)
				(type default)
			)
			(layer "B.SilkS")
		)
		(fp_line
			(start -0.7874 -0.4064)
			(end -0.7874 0.4064)
			(stroke
				(width 0.1524)
				(type default)
			)
			(layer "B.SilkS")
		)
		(fp_line
			(start 0.7874 0.4064)
			(end 0.7874 -0.4064)
			(stroke
				(width 0.1524)
				(type default)
			)
			(layer "B.SilkS")
		)
		(fp_line
			(start -0.7874 0.4064)
			(end 0.7874 0.4064)
			(stroke
				(width 0.1524)
				(type default)
			)
			(layer "B.SilkS")
		)
		(fp_line
			(start 0.67945 -0.305054)
			(end 0.12065 -0.305054)
			(stroke
				(width 0.1)
				(type default)
			)
			(layer "B.Fab")
		)
		(fp_line
			(start 0.12065 -0.305054)
			(end 0.12065 -0.2794)
			(stroke
				(width 0.1)
				(type default)
			)
			(layer "B.Fab")
		)
		(fp_line
			(start -0.12065 -0.3048)
			(end -0.67945 -0.3048)
			(stroke
				(width 0.1)
				(type default)
			)
			(layer "B.Fab")
		)
		(fp_line
			(start -0.67945 -0.3048)
			(end -0.67945 0.3048)
			(stroke
				(width 0.1)
				(type default)
			)
			(layer "B.Fab")
		)
		(fp_line
			(start 0.12065 -0.2794)
			(end -0.12065 -0.2794)
			(stroke
				(width 0.1)
				(type default)
			)
			(layer "B.Fab")
		)
		(fp_line
			(start -0.12065 -0.2794)
			(end -0.12065 -0.3048)
			(stroke
				(width 0.1)
				(type default)
			)
			(layer "B.Fab")
		)
		(fp_line
			(start 0.12065 0.2794)
			(end 0.12065 0.3048)
			(stroke
				(width 0.1)
				(type default)
			)
			(layer "B.Fab")
		)
		(fp_line
			(start -0.120396 0.2794)
			(end 0.12065 0.2794)
			(stroke
				(width 0.1)
				(type default)
			)
			(layer "B.Fab")
		)
		(fp_line
			(start 0.67945 0.3048)
			(end 0.67945 -0.305054)
			(stroke
				(width 0.1)
				(type default)
			)
			(layer "B.Fab")
		)
		(fp_line
			(start 0.12065 0.3048)
			(end 0.67945 0.3048)
			(stroke
				(width 0.1)
				(type default)
			)
			(layer "B.Fab")
		)
		(fp_line
			(start -0.120396 0.3048)
			(end -0.120396 0.2794)
			(stroke
				(width 0.1)
				(type default)
			)
			(layer "B.Fab")
		)
		(fp_line
			(start -0.67945 0.3048)
			(end -0.120396 0.3048)
			(stroke
				(width 0.1)
				(type default)
			)
			(layer "B.Fab")
		)
		(pad "1" smd circle
			(at 0.40005 0 270)
			(size 0 0)
			(layers "B.Cu" "B.Mask" "B.Paste")
			(net "P3V3_AUX")
		)
		(pad "2" smd circle
			(at -0.40005 0 270)
			(size 0 0)
			(layers "B.Cu" "B.Mask" "B.Paste")
			(net "PU_BMC_FWSPIABR_N")
		)
	)
)
